(kicad_pcb
	(version 20241229)
	(generator "pcbnew")
	(generator_version "9.0")
	(general
		(thickness 1.552)
		(legacy_teardrops no)
	)
	(paper "A4")
	(title_block
		(date "2023-07-25")
		(rev "1.1.4")
		(comment 9 "footprints 15-19 of 379")
	)
	(layers
		(0 "F.Cu" signal)
		(4 "In1.Cu" signal)
		(6 "In2.Cu" signal)
		(8 "In3.Cu" signal)
		(10 "In4.Cu" signal)
		(12 "In5.Cu" signal)
		(14 "In6.Cu" signal)
		(2 "B.Cu" signal)
		(9 "F.Adhes" user "F.Adhesive")
		(11 "B.Adhes" user "B.Adhesive")
		(13 "F.Paste" user)
		(15 "B.Paste" user)
		(5 "F.SilkS" user "F.Silkscreen")
		(7 "B.SilkS" user "B.Silkscreen")
		(1 "F.Mask" user)
		(3 "B.Mask" user)
		(17 "Dwgs.User" user "User.Drawings")
		(19 "Cmts.User" user "User.Comments")
		(21 "Eco1.User" user "User.Eco1")
		(23 "Eco2.User" user "User.Eco2")
		(25 "Edge.Cuts" user)
		(27 "Margin" user)
		(31 "F.CrtYd" user "F.Courtyard")
		(29 "B.CrtYd" user "B.Courtyard")
		(35 "F.Fab" user)
		(33 "B.Fab" user)
	)
	(footprint "antmicro-footprints:R_0805_2012Metric"
		(layer "F.Cu")
		(at 148.78 73.15)
		(property "Reference" "R41"
			(at 1.75 0.39 0)
			(layer "F.SilkS")
			(effects
				(font
					(size 0.65 0.65)
					(thickness 0.15)
				)
				(justify left bottom)
			)
		)
		(property "Value" "R_0R_0805"
			(at 0 1.8 0)
			(layer "F.Fab")
			(hide yes)
			(effects
				(font
					(size 0.7 0.7)
					(thickness 0.15)
				)
				(justify left bottom)
			)
		)
		(property "Datasheet" "https://www.vishay.com/docs/20035/dcrcwe3.pdf"
			(at 0 0 0)
			(layer "F.Fab")
			(hide yes)
			(effects
				(font
					(size 1.27 1.27)
					(thickness 0.15)
				)
			)
		)
		(property "Description" "Zero Ohm Resistor, Jumper, 0805 [2012 Metric], Thick Film, 125 mW, 2.5 A, Surface Mount Device"
			(at 0 0 0)
			(layer "F.Fab")
			(hide yes)
			(effects
				(font
					(size 1.27 1.27)
					(thickness 0.15)
				)
			)
		)
		(property "Author" "Antmicro"
			(at 0 0 0)
			(layer "F.Fab")
			(hide yes)
			(effects
				(font
					(size 1 1)
					(thickness 0.15)
				)
			)
		)
		(property "Current" "2.5A"
			(at 0 0 0)
			(layer "F.Fab")
			(hide yes)
			(effects
				(font
					(size 1 1)
					(thickness 0.15)
				)
			)
		)
		(property "License" "Apache-2.0"
			(at 0 0 0)
			(layer "F.Fab")
			(hide yes)
			(effects
				(font
					(size 1 1)
					(thickness 0.15)
				)
			)
		)
		(property "MPN" "CRCW08050000Z0EA"
			(at 0 0 0)
			(layer "F.Fab")
			(hide yes)
			(effects
				(font
					(size 1 1)
					(thickness 0.15)
				)
			)
		)
		(property "Manufacturer" "Vishay"
			(at 0 0 0)
			(layer "F.Fab")
			(hide yes)
			(effects
				(font
					(size 1 1)
					(thickness 0.15)
				)
			)
		)
		(property "Tolerance" "~"
			(at 0 0 0)
			(layer "F.Fab")
			(hide yes)
			(effects
				(font
					(size 1 1)
					(thickness 0.15)
				)
			)
		)
		(property "Val" "0R"
			(at 0 0 0)
			(layer "F.Fab")
			(hide yes)
			(effects
				(font
					(size 1 1)
					(thickness 0.15)
				)
			)
		)
		(sheetname "/Power Supply/")
		(sheetfile "supply.kicad_sch")
		(attr smd)
		(fp_line
			(start -0.32 0.699)
			(end 0.28 0.699)
			(stroke
				(width 0.15)
				(type solid)
			)
			(layer "F.SilkS")
		)
		(fp_line
			(start -0.3 -0.701)
			(end 0.298 -0.701)
			(stroke
				(width 0.15)
				(type solid)
			)
			(layer "F.SilkS")
		)
		(fp_rect
			(start 1.95 -0.9)
			(end -1.95 0.9)
			(stroke
				(width 0.05)
				(type default)
			)
			(fill no)
			(layer "F.CrtYd")
		)
		(fp_line
			(start -0.951 -0.682)
			(end 0.949 -0.682)
			(stroke
				(width 0.15)
				(type solid)
			)
			(layer "F.Fab")
		)
		(fp_line
			(start -0.951 -0.677)
			(end -0.951 0.675)
			(stroke
				(width 0.15)
				(type solid)
			)
			(layer "F.Fab")
		)
		(fp_line
			(start -0.951 0.68)
			(end 0.949 0.68)
			(stroke
				(width 0.15)
				(type solid)
			)
			(layer "F.Fab")
		)
		(fp_line
			(start 0.949 -0.677)
			(end 0.949 0.675)
			(stroke
				(width 0.15)
				(type solid)
			)
			(layer "F.Fab")
		)
		(fp_text user "Author: Antmicro"
			(at -1.9 4.4 0)
			(layer "F.Fab")
			(effects
				(font
					(size 0.7 0.7)
					(thickness 0.15)
				)
				(justify left bottom)
			)
		)
		(fp_text user "License: Apache-2.0"
			(at -1.9 5.75 0)
			(layer "F.Fab")
			(effects
				(font
					(size 0.7 0.7)
					(thickness 0.15)
				)
				(justify left bottom)
			)
		)
		(fp_text user "${REFERENCE}"
			(at -1.9 3.1 0)
			(layer "F.Fab")
			(effects
				(font
					(size 0.7 0.7)
					(thickness 0.15)
				)
				(justify left bottom)
			)
		)
		(pad "1" smd roundrect
			(at -1.1 0)
			(size 1.2 1.3)
			(layers "F.Cu" "F.Mask" "F.Paste")
			(roundrect_rratio 0.25)
			(net 273 "/Power Supply/1V0_OUT")
			(pintype "passive")
		)
		(pad "2" smd roundrect
			(at 1.1 0)
			(size 1.2 1.3)
			(layers "F.Cu" "F.Mask" "F.Paste")
			(roundrect_rratio 0.25)
			(net 4 "1V0_Power")
			(pintype "passive")
		)
	)
	(footprint "antmicro-footprints:SOT-23-3"
		(layer "F.Cu")
		(at 154.18 65.95 90)
		(property "Reference" "Q3"
			(at -1.8 -1.8 90)
			(layer "F.SilkS")
			(effects
				(font
					(size 0.65 0.65)
					(thickness 0.15)
				)
				(justify left bottom)
			)
		)
		(property "Value" "AO3401A"
			(at -1.9 2.7 90)
			(layer "F.Fab")
			(hide yes)
			(effects
				(font
					(size 0.7 0.7)
					(thickness 0.15)
				)
				(justify left bottom)
			)
		)
		(property "Datasheet" "http://aosmd.com/res/data_sheets/AO3401A.pdf"
			(at 0 0 90)
			(layer "F.Fab")
			(hide yes)
			(effects
				(font
					(size 1.27 1.27)
					(thickness 0.15)
				)
			)
		)
		(property "Description" "Power MOSFET, P Channel, 30 V, 4 A, 0.07 ohm, SOT-23, Surface Mount"
			(at 0 0 90)
			(layer "F.Fab")
			(hide yes)
			(effects
				(font
					(size 1.27 1.27)
					(thickness 0.15)
				)
			)
		)
		(property "Author" "Antmicro"
			(at 220.13 -88.23 0)
			(layer "F.Fab")
			(hide yes)
			(effects
				(font
					(size 1 1)
					(thickness 0.15)
				)
			)
		)
		(property "License" "Apache-2.0"
			(at 220.13 -88.23 0)
			(layer "F.Fab")
			(hide yes)
			(effects
				(font
					(size 1 1)
					(thickness 0.15)
				)
			)
		)
		(property "MPN" "AO3401A"
			(at 220.13 -88.23 0)
			(layer "F.Fab")
			(hide yes)
			(effects
				(font
					(size 1 1)
					(thickness 0.15)
				)
			)
		)
		(property "Manufacturer" "AOSMD"
			(at 220.13 -88.23 0)
			(layer "F.Fab")
			(hide yes)
			(effects
				(font
					(size 1 1)
					(thickness 0.15)
				)
			)
		)
		(sheetname "/Power Supply/")
		(sheetfile "supply.kicad_sch")
		(attr smd)
		(fp_line
			(start 0.7 -1.5)
			(end -0.7 -1.5)
			(stroke
				(width 0.15)
				(type solid)
			)
			(layer "F.SilkS")
		)
		(fp_line
			(start -0.85 -1.35)
			(end -0.7 -1.5)
			(stroke
				(width 0.15)
				(type solid)
			)
			(layer "F.SilkS")
		)
		(fp_line
			(start -1.45 -1.35)
			(end -0.85 -1.35)
			(stroke
				(width 0.15)
				(type solid)
			)
			(layer "F.SilkS")
		)
		(fp_line
			(start 0.7 -0.4)
			(end 0.7 -1.5)
			(stroke
				(width 0.15)
				(type solid)
			)
			(layer "F.SilkS")
		)
		(fp_line
			(start 0.7 0.4)
			(end 0.7 1.5)
			(stroke
				(width 0.15)
				(type solid)
			)
			(layer "F.SilkS")
		)
		(fp_line
			(start 0.7 1.5)
			(end -0.7 1.5)
			(stroke
				(width 0.15)
				(type solid)
			)
			(layer "F.SilkS")
		)
		(fp_line
			(start -0.7 1.5)
			(end -0.7 1.35)
			(stroke
				(width 0.15)
				(type solid)
			)
			(layer "F.SilkS")
		)
		(fp_line
			(start 0.825 -1.6)
			(end 0.825 -0.45)
			(stroke
				(width 0.05)
				(type solid)
			)
			(layer "F.CrtYd")
		)
		(fp_line
			(start -0.9 -1.6)
			(end 0.825 -1.6)
			(stroke
				(width 0.05)
				(type solid)
			)
			(layer "F.CrtYd")
		)
		(fp_line
			(start -0.9 -1.6)
			(end -0.9 -1.4)
			(stroke
				(width 0.05)
				(type solid)
			)
			(layer "F.CrtYd")
		)
		(fp_line
			(start -0.9 -1.4)
			(end -1.75 -1.4)
			(stroke
				(width 0.05)
				(type solid)
			)
			(layer "F.CrtYd")
		)
		(fp_line
			(start -0.85 -0.5)
			(end -1.75 -0.5)
			(stroke
				(width 0.05)
				(type solid)
			)
			(layer "F.CrtYd")
		)
		(fp_line
			(start -1.75 -0.5)
			(end -1.75 -1.4)
			(stroke
				(width 0.05)
				(type solid)
			)
			(layer "F.CrtYd")
		)
		(fp_line
			(start 1.75 -0.45)
			(end 1.75 0.45)
			(stroke
				(width 0.05)
				(type solid)
			)
			(layer "F.CrtYd")
		)
		(fp_line
			(start 0.825 -0.45)
			(end 1.75 -0.45)
			(stroke
				(width 0.05)
				(type solid)
			)
			(layer "F.CrtYd")
		)
		(fp_line
			(start 1.75 0.45)
			(end 0.85 0.45)
			(stroke
				(width 0.05)
				(type solid)
			)
			(layer "F.CrtYd")
		)
		(fp_line
			(start 0.85 0.45)
			(end 0.85 1.65)
			(stroke
				(width 0.05)
				(type solid)
			)
			(layer "F.CrtYd")
		)
		(fp_line
			(start -0.85 0.5)
			(end -0.85 -0.5)
			(stroke
				(width 0.05)
				(type solid)
			)
			(layer "F.CrtYd")
		)
		(fp_line
			(start -1.75 0.5)
			(end -0.85 0.5)
			(stroke
				(width 0.05)
				(type solid)
			)
			(layer "F.CrtYd")
		)
		(fp_line
			(start -0.85 1.4)
			(end -1.75 1.4)
			(stroke
				(width 0.05)
				(type solid)
			)
			(layer "F.CrtYd")
		)
		(fp_line
			(start -1.75 1.4)
			(end -1.75 0.5)
			(stroke
				(width 0.05)
				(type solid)
			)
			(layer "F.CrtYd")
		)
		(fp_line
			(start 0.85 1.65)
			(end -0.85 1.65)
			(stroke
				(width 0.05)
				(type solid)
			)
			(layer "F.CrtYd")
		)
		(fp_line
			(start -0.85 1.65)
			(end -0.85 1.4)
			(stroke
				(width 0.05)
				(type solid)
			)
			(layer "F.CrtYd")
		)
		(fp_line
			(start -0.437 -1.526)
			(end 0.688 -1.526)
			(stroke
				(width 0.15)
				(type solid)
			)
			(layer "F.Fab")
		)
		(fp_line
			(start -0.437 -1.526)
			(end -0.712 -1.325)
			(stroke
				(width 0.15)
				(type solid)
			)
			(layer "F.Fab")
		)
		(fp_line
			(start -0.712 -1.325)
			(end -0.712 1.523)
			(stroke
				(width 0.15)
				(type solid)
			)
			(layer "F.Fab")
		)
		(fp_line
			(start 0.688 1.519)
			(end 0.688 -1.52)
			(stroke
				(width 0.15)
				(type solid)
			)
			(layer "F.Fab")
		)
		(fp_line
			(start -0.712 1.519)
			(end 0.688 1.519)
			(stroke
				(width 0.15)
				(type solid)
			)
			(layer "F.Fab")
		)
		(pad "1" smd roundrect
			(at -1.1 -0.951 90)
			(size 1 0.6)
			(layers "F.Cu" "F.Mask" "F.Paste")
			(roundrect_rratio 0.15)
			(net 260 "Net-(Q3-G)")
			(pinfunction "G")
			(pintype "input")
		)
		(pad "2" smd roundrect
			(at -1.1 0.949 90)
			(size 1 0.6)
			(layers "F.Cu" "F.Mask" "F.Paste")
			(roundrect_rratio 0.15)
			(net 304 "/Power Supply/5V_I")
			(pinfunction "S")
			(pintype "passive")
		)
		(pad "3" smd roundrect
			(at 1.1 -0.0005 90)
			(size 1 0.6)
			(layers "F.Cu" "F.Mask" "F.Paste")
			(roundrect_rratio 0.15)
			(net 325 "USB_POWER_IN")
			(pinfunction "D")
			(pintype "passive")
		)
	)
	(footprint "antmicro-footprints:R_0402_1005Metric"
		(layer "F.Cu")
		(at 108.4 107.2 90)
		(descr "Resistor SMD 0402")
		(tags "resistor SMD 0402")
		(property "Reference" "R141"
			(at -3.84 0.43 90)
			(layer "F.SilkS")
			(effects
				(font
					(size 0.65 0.65)
					(thickness 0.15)
				)
				(justify left bottom)
			)
		)
		(property "Value" "R_0R_0402"
			(at 0 1.4 90)
			(layer "F.Fab")
			(hide yes)
			(effects
				(font
					(size 0.7 0.7)
					(thickness 0.15)
				)
				(justify left bottom)
			)
		)
		(property "Datasheet" "https://industrial.panasonic.com/cdbs/www-data/pdf/RDA0000/AOA0000C301.pdf"
			(at 0 0 90)
			(layer "F.Fab")
			(hide yes)
			(effects
				(font
					(size 1.27 1.27)
					(thickness 0.15)
				)
			)
		)
		(property "Description" "SMD Chip Resistor, Jumper, 0 ohm, 100 mW, 0402 [1005 Metric], Thick Film, General Purpose"
			(at 0 0 90)
			(layer "F.Fab")
			(hide yes)
			(effects
				(font
					(size 1.27 1.27)
					(thickness 0.15)
				)
			)
		)
		(property "Author" "Antmicro"
			(at 215.6 -1.2 0)
			(layer "F.Fab")
			(hide yes)
			(effects
				(font
					(size 1 1)
					(thickness 0.15)
				)
			)
		)
		(property "Current" "1A"
			(at 215.6 -1.2 0)
			(layer "F.Fab")
			(hide yes)
			(effects
				(font
					(size 1 1)
					(thickness 0.15)
				)
			)
		)
		(property "License" "Apache-2.0"
			(at 215.6 -1.2 0)
			(layer "F.Fab")
			(hide yes)
			(effects
				(font
					(size 1 1)
					(thickness 0.15)
				)
			)
		)
		(property "MPN" "ERJ2GE0R00X"
			(at 215.6 -1.2 0)
			(layer "F.Fab")
			(hide yes)
			(effects
				(font
					(size 1 1)
					(thickness 0.15)
				)
			)
		)
		(property "Manufacturer" "Panasonic"
			(at 215.6 -1.2 0)
			(layer "F.Fab")
			(hide yes)
			(effects
				(font
					(size 1 1)
					(thickness 0.15)
				)
			)
		)
		(property "Tolerance" "~"
			(at 215.6 -1.2 0)
			(layer "F.Fab")
			(hide yes)
			(effects
				(font
					(size 1 1)
					(thickness 0.15)
				)
			)
		)
		(property "Val" "0R"
			(at 215.6 -1.2 0)
			(layer "F.Fab")
			(hide yes)
			(effects
				(font
					(size 1 1)
					(thickness 0.15)
				)
			)
		)
		(sheetname "/FPGA/")
		(sheetfile "fpga.kicad_sch")
		(attr smd)
		(fp_rect
			(start -0.925 -0.47)
			(end 0.925 0.47)
			(stroke
				(width 0.05)
				(type default)
			)
			(fill no)
			(layer "F.CrtYd")
		)
		(fp_rect
			(start -0.5 -0.25)
			(end 0.5 0.25)
			(stroke
				(width 0.15)
				(type solid)
			)
			(fill no)
			(layer "F.Fab")
		)
		(fp_text user "Author: Antmicro"
			(at -0.95 4.169 90)
			(layer "F.Fab")
			(effects
				(font
					(size 0.7 0.7)
					(thickness 0.15)
				)
				(justify left bottom)
			)
		)
		(fp_text user "${REFERENCE}"
			(at -0.95 3.168 90)
			(layer "F.Fab")
			(effects
				(font
					(size 0.7 0.7)
					(thickness 0.15)
				)
				(justify left bottom)
			)
		)
		(fp_text user "License: Apache-2.0"
			(at -0.95 5.169 90)
			(layer "F.Fab")
			(effects
				(font
					(size 0.7 0.7)
					(thickness 0.15)
				)
				(justify left bottom)
			)
		)
		(pad "1" smd roundrect
			(at -0.48 0 90)
			(size 0.59 0.64)
			(layers "F.Cu" "F.Mask" "F.Paste")
			(roundrect_rratio 0.25)
			(net 363 "/FPGA/DONE_SOFT")
			(pintype "passive")
		)
		(pad "2" smd roundrect
			(at 0.48 0 90)
			(size 0.59 0.64)
			(layers "F.Cu" "F.Mask" "F.Paste")
			(roundrect_rratio 0.25)
			(net 358 "Net-(U17-GPIO2{slash}~{SS2})")
			(pintype "passive")
		)
	)
	(footprint "antmicro-footprints:TP_SMD_0.75mm"
		(layer "F.Cu")
		(at 106.3492 99.7 -90)
		(property "Reference" "TP18"
			(at -0.31 2.8892 0)
			(layer "F.SilkS")
			(effects
				(font
					(size 0.65 0.65)
					(thickness 0.15)
				)
				(justify left top)
			)
		)
		(property "Value" "TP_0.75mm_SMD"
			(at 0 1.2 90)
			(layer "F.Fab")
			(hide yes)
			(effects
				(font
					(size 0.7 0.7)
					(thickness 0.15)
				)
				(justify right bottom)
			)
		)
		(property "Description" "SMT test point"
			(at 0 0 90)
			(layer "F.Fab")
			(hide yes)
			(effects
				(font
					(size 1.27 1.27)
					(thickness 0.15)
				)
			)
		)
		(property "Author" "Antmicro"
			(at 6.6492 206.0492 0)
			(layer "F.Fab")
			(hide yes)
			(effects
				(font
					(size 1 1)
					(thickness 0.15)
				)
			)
		)
		(property "License" "Apache-2.0"
			(at 6.6492 206.0492 0)
			(layer "F.Fab")
			(hide yes)
			(effects
				(font
					(size 1 1)
					(thickness 0.15)
				)
			)
		)
		(property "MPN" ""
			(at 6.6492 206.0492 0)
			(layer "F.Fab")
			(hide yes)
			(effects
				(font
					(size 1 1)
					(thickness 0.15)
				)
			)
		)
		(property "Manufacturer" ""
			(at 6.6492 206.0492 0)
			(layer "F.Fab")
			(hide yes)
			(effects
				(font
					(size 1 1)
					(thickness 0.15)
				)
			)
		)
		(sheetname "/FPGA/")
		(sheetfile "fpga.kicad_sch")
		(attr exclude_from_pos_files)
		(fp_circle
			(center 0 0)
			(end 0.475 0)
			(stroke
				(width 0.05)
				(type default)
			)
			(fill no)
			(layer "F.CrtYd")
		)
		(fp_text user "License: Apache-2.0"
			(at -0.4 5.101 90)
			(layer "F.Fab")
			(effects
				(font
					(size 0.7 0.7)
					(thickness 0.15)
				)
				(justify right top)
			)
		)
		(fp_text user "${REFERENCE}"
			(at -0.4 2.7 90)
			(layer "F.Fab")
			(effects
				(font
					(size 0.7 0.7)
					(thickness 0.15)
				)
				(justify right top)
			)
		)
		(fp_text user "Author: Antmicro"
			(at -0.4 3.901 90)
			(layer "F.Fab")
			(effects
				(font
					(size 0.7 0.7)
					(thickness 0.15)
				)
				(justify right top)
			)
		)
		(pad "1" smd circle
			(at 0 0 270)
			(size 0.75 0.75)
			(layers "F.Cu" "F.Mask")
			(net 27 "/FPGA/SPI_DQ3")
			(pinfunction "1")
			(pintype "passive")
		)
	)
	(footprint "antmicro-footprints:TP_SMD_0.75mm"
		(layer "F.Cu")
		(at 146.54 56.6508)
		(property "Reference" "TP11"
			(at -0.11 -0.5108 0)
			(layer "F.SilkS")
			(effects
				(font
					(size 0.65 0.65)
					(thickness 0.15)
				)
				(justify left bottom)
			)
		)
		(property "Value" "TP_0.75mm_SMD"
			(at 0 1.2 0)
			(layer "F.Fab")
			(hide yes)
			(effects
				(font
					(size 0.7 0.7)
					(thickness 0.15)
				)
				(justify left bottom)
			)
		)
		(property "Description" "SMT test point"
			(at 0 0 0)
			(layer "F.Fab")
			(hide yes)
			(effects
				(font
					(size 1.27 1.27)
					(thickness 0.15)
				)
			)
		)
		(property "Author" "Antmicro"
			(at 0 0 0)
			(layer "F.Fab")
			(hide yes)
			(effects
				(font
					(size 1 1)
					(thickness 0.15)
				)
			)
		)
		(property "License" "Apache-2.0"
			(at 0 0 0)
			(layer "F.Fab")
			(hide yes)
			(effects
				(font
					(size 1 1)
					(thickness 0.15)
				)
			)
		)
		(property "MPN" ""
			(at 0 0 0)
			(layer "F.Fab")
			(hide yes)
			(effects
				(font
					(size 1 1)
					(thickness 0.15)
				)
			)
		)
		(property "Manufacturer" ""
			(at 0 0 0)
			(layer "F.Fab")
			(hide yes)
			(effects
				(font
					(size 1 1)
					(thickness 0.15)
				)
			)
		)
		(sheetname "/Power Supply/")
		(sheetfile "supply.kicad_sch")
		(attr exclude_from_pos_files)
		(fp_circle
			(center 0 0)
			(end 0.475 0)
			(stroke
				(width 0.05)
				(type default)
			)
			(fill no)
			(layer "F.CrtYd")
		)
		(fp_text user "${REFERENCE}"
			(at -0.4 2.7 0)
			(layer "F.Fab")
			(effects
				(font
					(size 0.7 0.7)
					(thickness 0.15)
				)
				(justify left bottom)
			)
		)
		(fp_text user "Author: Antmicro"
			(at -0.4 3.901 0)
			(layer "F.Fab")
			(effects
				(font
					(size 0.7 0.7)
					(thickness 0.15)
				)
				(justify left bottom)
			)
		)
		(fp_text user "License: Apache-2.0"
			(at -0.4 5.101 0)
			(layer "F.Fab")
			(effects
				(font
					(size 0.7 0.7)
					(thickness 0.15)
				)
				(justify left bottom)
			)
		)
		(pad "1" smd circle
			(at 0 0)
			(size 0.75 0.75)
			(layers "F.Cu" "F.Mask")
			(net 374 "Net-(U6-EN)")
			(pinfunction "1")
			(pintype "passive")
		)
	)
)
